(kicad_pcb
	(version 20260206)
	(generator "pcbnew")
	(generator_version "10.0")
	(general
		(thickness 1.6)
		(legacy_teardrops no)
	)
	(paper "A4")
	(title_block
		(title "01162023_DA0F0TEBIF0_F0T_Expander_BD_F_brd_V02_OCP.brd")
		(comment 1 "Grand Teton / footprints 2035-2041 of 9728")
	)
	(layers
		(0 "F.Cu" signal "TOP")
		(4 "In1.Cu" signal "GND")
		(6 "In2.Cu" signal "VCC")
		(8 "In3.Cu" signal "VCC1")
		(10 "In4.Cu" signal "GND1")
		(12 "In5.Cu" signal "IN1")
		(14 "In6.Cu" signal "GND2")
		(16 "In7.Cu" signal "IN2")
		(18 "In8.Cu" signal "GND3")
		(20 "In9.Cu" signal "IN3")
		(22 "In10.Cu" signal "GND4")
		(24 "In11.Cu" signal "IN4")
		(26 "In12.Cu" signal "GND5")
		(28 "In13.Cu" signal "IN5")
		(30 "In14.Cu" signal "GND6")
		(32 "In15.Cu" signal "IN6")
		(34 "In16.Cu" signal "GND7")
		(2 "B.Cu" signal "BOTTOM")
		(9 "F.Adhes" user "F.Adhesive")
		(11 "B.Adhes" user "B.Adhesive")
		(13 "F.Paste" user "Package Geometry/Pastemask Top")
		(15 "B.Paste" user "Package Geometry/Pastemask Bottom")
		(5 "F.SilkS" user "Ref Des/Silkscreen Top")
		(7 "B.SilkS" user "Ref Des/Silkscreen Bottom")
		(1 "F.Mask" user "Board Geometry/Soldermask Top")
		(3 "B.Mask" user "Board Geometry/Soldermask Bottom")
		(17 "Dwgs.User" user "User.Drawings")
		(19 "Cmts.User" user "User.Comments")
		(21 "Eco1.User" user "User.Eco1")
		(23 "Eco2.User" user "User.Eco2")
		(25 "Edge.Cuts" user "Board Geometry/Outline")
		(27 "Margin" user)
		(31 "F.CrtYd" user "Package Geometry/Place Bound Top")
		(29 "B.CrtYd" user "Package Geometry/Place Bound Bottom")
		(35 "F.Fab" user "Ref Des/Assembly Top")
		(33 "B.Fab" user "Ref Des/Assembly Bottom")
	)
	(footprint ""
		(layer "F.Cu")
		(at 208.150206 -306.074572 90)
		(property "Reference" "R1309"
			(at 0 0 90)
			(layer "F.SilkS")
			(hide yes)
			(effects
				(font
					(size 1.27 1.27)
				)
			)
		)
		(property "Value" ""
			(at 0 0 90)
			(layer "F.Fab")
			(effects
				(font
					(size 1.27 1.27)
				)
			)
		)
		(duplicate_pad_numbers_are_jumpers no)
		(fp_line
			(start 0.7874 -0.4064)
			(end 0.7874 0.4064)
			(stroke
				(width 0.1524)
				(type default)
			)
			(layer "F.SilkS")
		)
		(fp_line
			(start -0.7874 -0.4064)
			(end 0.7874 -0.4064)
			(stroke
				(width 0.1524)
				(type default)
			)
			(layer "F.SilkS")
		)
		(fp_line
			(start 0.7874 0.4064)
			(end -0.7874 0.4064)
			(stroke
				(width 0.1524)
				(type default)
			)
			(layer "F.SilkS")
		)
		(fp_line
			(start -0.7874 0.4064)
			(end -0.7874 -0.4064)
			(stroke
				(width 0.1524)
				(type default)
			)
			(layer "F.SilkS")
		)
		(fp_line
			(start -0.12065 -0.305054)
			(end -0.12065 -0.2794)
			(stroke
				(width 0.1)
				(type default)
			)
			(layer "F.Fab")
		)
		(fp_line
			(start -0.67945 -0.305054)
			(end -0.12065 -0.305054)
			(stroke
				(width 0.1)
				(type default)
			)
			(layer "F.Fab")
		)
		(fp_line
			(start 0.67945 -0.3048)
			(end 0.67945 0.3048)
			(stroke
				(width 0.1)
				(type default)
			)
			(layer "F.Fab")
		)
		(fp_line
			(start 0.12065 -0.3048)
			(end 0.67945 -0.3048)
			(stroke
				(width 0.1)
				(type default)
			)
			(layer "F.Fab")
		)
		(fp_line
			(start 0.12065 -0.2794)
			(end 0.12065 -0.3048)
			(stroke
				(width 0.1)
				(type default)
			)
			(layer "F.Fab")
		)
		(fp_line
			(start -0.12065 -0.2794)
			(end 0.12065 -0.2794)
			(stroke
				(width 0.1)
				(type default)
			)
			(layer "F.Fab")
		)
		(fp_line
			(start 0.120396 0.2794)
			(end -0.12065 0.2794)
			(stroke
				(width 0.1)
				(type default)
			)
			(layer "F.Fab")
		)
		(fp_line
			(start -0.12065 0.2794)
			(end -0.12065 0.3048)
			(stroke
				(width 0.1)
				(type default)
			)
			(layer "F.Fab")
		)
		(fp_line
			(start 0.67945 0.3048)
			(end 0.120396 0.3048)
			(stroke
				(width 0.1)
				(type default)
			)
			(layer "F.Fab")
		)
		(fp_line
			(start 0.120396 0.3048)
			(end 0.120396 0.2794)
			(stroke
				(width 0.1)
				(type default)
			)
			(layer "F.Fab")
		)
		(fp_line
			(start -0.12065 0.3048)
			(end -0.67945 0.3048)
			(stroke
				(width 0.1)
				(type default)
			)
			(layer "F.Fab")
		)
		(fp_line
			(start -0.67945 0.3048)
			(end -0.67945 -0.305054)
			(stroke
				(width 0.1)
				(type default)
			)
			(layer "F.Fab")
		)
		(pad "1" smd circle
			(at -0.40005 0 90)
			(size 0 0)
			(layers "F.Cu" "F.Mask" "F.Paste")
			(net "PEX1_SPARE6")
		)
		(pad "2" smd circle
			(at 0.40005 0 90)
			(size 0 0)
			(layers "F.Cu" "F.Mask" "F.Paste")
			(net "P1V8_PEX")
		)
	)
	(footprint ""
		(layer "F.Cu")
		(at 101.601016 -303.649634 90)
		(property "Reference" "PC68"
			(at 0 0 90)
			(layer "F.SilkS")
			(hide yes)
			(effects
				(font
					(size 1.27 1.27)
				)
			)
		)
		(property "Value" ""
			(at 0 0 90)
			(layer "F.Fab")
			(effects
				(font
					(size 1.27 1.27)
				)
			)
		)
		(duplicate_pad_numbers_are_jumpers no)
		(fp_line
			(start 1.524 -0.762)
			(end 1.524 0.762)
			(stroke
				(width 0.1524)
				(type default)
			)
			(layer "F.SilkS")
		)
		(fp_line
			(start -1.524 -0.762)
			(end 1.524 -0.762)
			(stroke
				(width 0.1524)
				(type default)
			)
			(layer "F.SilkS")
		)
		(fp_line
			(start 1.524 0.762)
			(end -1.524 0.762)
			(stroke
				(width 0.1524)
				(type default)
			)
			(layer "F.SilkS")
		)
		(fp_line
			(start -1.524 0.762)
			(end -1.524 -0.762)
			(stroke
				(width 0.1524)
				(type default)
			)
			(layer "F.SilkS")
		)
		(fp_line
			(start 1.1049 -0.724916)
			(end -1.1049 -0.724916)
			(stroke
				(width 0.1)
				(type default)
			)
			(layer "F.Fab")
		)
		(fp_line
			(start -1.1049 -0.724916)
			(end -1.1049 0.724916)
			(stroke
				(width 0.1)
				(type default)
			)
			(layer "F.Fab")
		)
		(fp_line
			(start 1.1049 0.724916)
			(end 1.1049 -0.724916)
			(stroke
				(width 0.1)
				(type default)
			)
			(layer "F.Fab")
		)
		(fp_line
			(start -1.1049 0.724916)
			(end 1.1049 0.724916)
			(stroke
				(width 0.1)
				(type default)
			)
			(layer "F.Fab")
		)
		(pad "1" smd rect
			(at -0.889 0 270)
			(size 1.016 1.27)
			(layers "F.Cu" "F.Mask" "F.Paste")
			(net "P0V8_PEX0")
		)
		(pad "2" smd rect
			(at 0.889 0 270)
			(size 1.016 1.27)
			(layers "F.Cu" "F.Mask" "F.Paste")
			(net "GND")
		)
	)
	(footprint ""
		(layer "F.Cu")
		(at 118.969028 -350.098614 90)
		(property "Reference" "C363"
			(at 0 0 90)
			(layer "F.SilkS")
			(hide yes)
			(effects
				(font
					(size 1.27 1.27)
				)
			)
		)
		(property "Value" ""
			(at 0 0 90)
			(layer "F.Fab")
			(effects
				(font
					(size 1.27 1.27)
				)
			)
		)
		(duplicate_pad_numbers_are_jumpers no)
		(fp_line
			(start 0.299974 -0.150114)
			(end 0.299974 0.150114)
			(stroke
				(width 0.1)
				(type default)
			)
			(layer "F.Fab")
		)
		(fp_line
			(start -0.299974 -0.150114)
			(end 0.299974 -0.150114)
			(stroke
				(width 0.1)
				(type default)
			)
			(layer "F.Fab")
		)
		(fp_line
			(start 0.299974 0.150114)
			(end -0.299974 0.150114)
			(stroke
				(width 0.1)
				(type default)
			)
			(layer "F.Fab")
		)
		(fp_line
			(start -0.299974 0.150114)
			(end -0.299974 -0.150114)
			(stroke
				(width 0.1)
				(type default)
			)
			(layer "F.Fab")
		)
		(pad "1" smd rect
			(at -0.2667 0 90)
			(size 0.3048 0.381)
			(layers "F.Cu" "F.Mask" "F.Paste")
			(net "P5E_PEX1_STN6_TX_DN<100>")
		)
		(pad "2" smd rect
			(at 0.2667 0 90)
			(size 0.3048 0.381)
			(layers "F.Cu" "F.Mask" "F.Paste")
			(net "P5E_PEX1_STN6_TX_C_DN<100>")
		)
	)
	(footprint ""
		(layer "F.Cu")
		(at 329.438 -82.931 180)
		(property "Reference" "R6259"
			(at 0 0 180)
			(layer "F.SilkS")
			(hide yes)
			(effects
				(font
					(size 1.27 1.27)
				)
			)
		)
		(property "Value" ""
			(at 0 0 180)
			(layer "F.Fab")
			(effects
				(font
					(size 1.27 1.27)
				)
			)
		)
		(duplicate_pad_numbers_are_jumpers no)
		(fp_line
			(start 0.7874 0.4064)
			(end -0.7874 0.4064)
			(stroke
				(width 0.1524)
				(type default)
			)
			(layer "F.SilkS")
		)
		(fp_line
			(start 0.7874 -0.4064)
			(end 0.7874 0.4064)
			(stroke
				(width 0.1524)
				(type default)
			)
			(layer "F.SilkS")
		)
		(fp_line
			(start -0.7874 0.4064)
			(end -0.7874 -0.4064)
			(stroke
				(width 0.1524)
				(type default)
			)
			(layer "F.SilkS")
		)
		(fp_line
			(start -0.7874 -0.4064)
			(end 0.7874 -0.4064)
			(stroke
				(width 0.1524)
				(type default)
			)
			(layer "F.SilkS")
		)
		(fp_line
			(start 0.67945 0.3048)
			(end 0.120396 0.3048)
			(stroke
				(width 0.1)
				(type default)
			)
			(layer "F.Fab")
		)
		(fp_line
			(start 0.67945 -0.3048)
			(end 0.67945 0.3048)
			(stroke
				(width 0.1)
				(type default)
			)
			(layer "F.Fab")
		)
		(fp_line
			(start 0.12065 -0.2794)
			(end 0.12065 -0.3048)
			(stroke
				(width 0.1)
				(type default)
			)
			(layer "F.Fab")
		)
		(fp_line
			(start 0.12065 -0.3048)
			(end 0.67945 -0.3048)
			(stroke
				(width 0.1)
				(type default)
			)
			(layer "F.Fab")
		)
		(fp_line
			(start 0.120396 0.3048)
			(end 0.120396 0.2794)
			(stroke
				(width 0.1)
				(type default)
			)
			(layer "F.Fab")
		)
		(fp_line
			(start 0.120396 0.2794)
			(end -0.12065 0.2794)
			(stroke
				(width 0.1)
				(type default)
			)
			(layer "F.Fab")
		)
		(fp_line
			(start -0.12065 0.3048)
			(end -0.67945 0.3048)
			(stroke
				(width 0.1)
				(type default)
			)
			(layer "F.Fab")
		)
		(fp_line
			(start -0.12065 0.2794)
			(end -0.12065 0.3048)
			(stroke
				(width 0.1)
				(type default)
			)
			(layer "F.Fab")
		)
		(fp_line
			(start -0.12065 -0.2794)
			(end 0.12065 -0.2794)
			(stroke
				(width 0.1)
				(type default)
			)
			(layer "F.Fab")
		)
		(fp_line
			(start -0.12065 -0.305054)
			(end -0.12065 -0.2794)
			(stroke
				(width 0.1)
				(type default)
			)
			(layer "F.Fab")
		)
		(fp_line
			(start -0.67945 0.3048)
			(end -0.67945 -0.305054)
			(stroke
				(width 0.1)
				(type default)
			)
			(layer "F.Fab")
		)
		(fp_line
			(start -0.67945 -0.305054)
			(end -0.12065 -0.305054)
			(stroke
				(width 0.1)
				(type default)
			)
			(layer "F.Fab")
		)
		(pad "1" smd circle
			(at -0.40005 0 180)
			(size 0 0)
			(layers "F.Cu" "F.Mask" "F.Paste")
			(net "SMB_ISO_CB_SCL")
		)
		(pad "2" smd circle
			(at 0.40005 0 180)
			(size 0 0)
			(layers "F.Cu" "F.Mask" "F.Paste")
			(net "P3V3")
		)
	)
	(footprint ""
		(layer "F.Cu")
		(at 269.448026 -101.095302)
		(property "Reference" "C483"
			(at 0 0 0)
			(layer "F.SilkS")
			(hide yes)
			(effects
				(font
					(size 1.27 1.27)
				)
			)
		)
		(property "Value" ""
			(at 0 0 0)
			(layer "F.Fab")
			(effects
				(font
					(size 1.27 1.27)
				)
			)
		)
		(duplicate_pad_numbers_are_jumpers no)
		(fp_line
			(start -0.299974 -0.150114)
			(end 0.299974 -0.150114)
			(stroke
				(width 0.1)
				(type default)
			)
			(layer "F.Fab")
		)
		(fp_line
			(start -0.299974 0.150114)
			(end -0.299974 -0.150114)
			(stroke
				(width 0.1)
				(type default)
			)
			(layer "F.Fab")
		)
		(fp_line
			(start 0.299974 -0.150114)
			(end 0.299974 0.150114)
			(stroke
				(width 0.1)
				(type default)
			)
			(layer "F.Fab")
		)
		(fp_line
			(start 0.299974 0.150114)
			(end -0.299974 0.150114)
			(stroke
				(width 0.1)
				(type default)
			)
			(layer "F.Fab")
		)
		(pad "1" smd rect
			(at -0.2667 0)
			(size 0.3048 0.381)
			(layers "F.Cu" "F.Mask" "F.Paste")
			(net "P5E_PEX2_STN1_TX_DN<17>")
		)
		(pad "2" smd rect
			(at 0.2667 0)
			(size 0.3048 0.381)
			(layers "F.Cu" "F.Mask" "F.Paste")
			(net "P5E_PEX2_STN1_TX_C_DN<17>")
		)
	)
	(footprint ""
		(layer "F.Cu")
		(at 323.8246 -115.835176 90)
		(property "Reference" "PU120"
			(at 1.613154 -3.429 0)
			(unlocked yes)
			(layer "F.SilkS")
			(effects
				(font
					(size 0.7874 0.5842)
					(thickness 0.1524)
				)
			)
		)
		(property "Value" ""
			(at 0 0 90)
			(layer "F.Fab")
			(effects
				(font
					(size 1.27 1.27)
				)
			)
		)
		(duplicate_pad_numbers_are_jumpers no)
		(fp_line
			(start 1.239774 -1.495298)
			(end 1.239774 1.495298)
			(stroke
				(width 0.1524)
				(type default)
			)
			(layer "F.SilkS")
		)
		(fp_line
			(start -1.239774 -1.495298)
			(end 1.239774 -1.495298)
			(stroke
				(width 0.1524)
				(type default)
			)
			(layer "F.SilkS")
		)
		(fp_line
			(start 1.239774 1.495298)
			(end -1.239774 1.495298)
			(stroke
				(width 0.1524)
				(type default)
			)
			(layer "F.SilkS")
		)
		(fp_line
			(start -1.239774 1.495298)
			(end -1.239774 -1.495298)
			(stroke
				(width 0.1524)
				(type default)
			)
			(layer "F.SilkS")
		)
		(fp_poly
			(pts
				(xy -2.164588 -1.709928) (xy -2.8829 -0.991616) (xy -1.805432 -0.63246)
			)
			(stroke
				(width 0)
				(type default)
			)
			(fill yes)
			(layer "F.SilkS")
		)
		(fp_line
			(start 0.8001 -1.050036)
			(end 0.8001 1.050036)
			(stroke
				(width 0.1)
				(type default)
			)
			(layer "F.Fab")
		)
		(fp_line
			(start -0.8001 -1.050036)
			(end 0.8001 -1.050036)
			(stroke
				(width 0.1)
				(type default)
			)
			(layer "F.Fab")
		)
		(fp_line
			(start 0.8001 1.050036)
			(end -0.8001 1.050036)
			(stroke
				(width 0.1)
				(type default)
			)
			(layer "F.Fab")
		)
		(fp_line
			(start -0.8001 1.050036)
			(end -0.8001 -1.050036)
			(stroke
				(width 0.1)
				(type default)
			)
			(layer "F.Fab")
		)
		(fp_poly
			(pts
				(xy -2.458974 -0.508) (xy -2.458974 0.508) (xy -1.442974 0)
			)
			(stroke
				(width 0)
				(type default)
			)
			(fill yes)
			(layer "F.Fab")
		)
		(pad "1_2" smd circle
			(at -0.374904 0 180)
			(size 0 0)
			(layers "F.Cu" "F.Mask" "F.Paste")
			(net "P3V3_AUX")
		)
		(pad "3" smd rect
			(at -0.499872 0.999998 90)
			(size 0.254 0.7112)
			(layers "F.Cu" "F.Mask" "F.Paste")
			(net "GND")
		)
		(pad "4" smd rect
			(at 0 0.999998 90)
			(size 0.254 0.7112)
			(layers "F.Cu" "F.Mask" "F.Paste")
			(net "P3V3_NIC5_CO_ILIMIT")
		)
		(pad "5" smd rect
			(at 0.499872 0.999998 90)
			(size 0.254 0.7112)
			(layers "F.Cu" "F.Mask" "F.Paste")
			(net "P3V3_NIC5_CO_MODE")
		)
		(pad "6_7" smd circle
			(at 0.374904 0)
			(size 0 0)
			(layers "F.Cu" "F.Mask" "F.Paste")
			(net "P3V3_NIC5")
		)
		(pad "8" smd rect
			(at 0.499872 -0.999998 90)
			(size 0.254 0.7112)
			(layers "F.Cu" "F.Mask" "F.Paste")
			(net "P3V3_NIC5_CO_GATE")
		)
		(pad "9" smd rect
			(at 0 -0.999998 90)
			(size 0.254 0.7112)
			(layers "F.Cu" "F.Mask" "F.Paste")
			(net "P3V3_NIC5_CO_EN")
		)
		(pad "10" smd rect
			(at -0.499872 -0.999998 90)
			(size 0.254 0.7112)
			(layers "F.Cu" "F.Mask" "F.Paste")
			(net "P3V3_NIC5_CO_DV_DT")
		)
	)
	(footprint ""
		(layer "F.Cu")
		(at 38.566344 -252.356874 -90)
		(property "Reference" "R1189"
			(at 0 0 270)
			(layer "F.SilkS")
			(hide yes)
			(effects
				(font
					(size 1.27 1.27)
				)
			)
		)
		(property "Value" ""
			(at 0 0 270)
			(layer "F.Fab")
			(effects
				(font
					(size 1.27 1.27)
				)
			)
		)
		(duplicate_pad_numbers_are_jumpers no)
		(fp_line
			(start -0.7874 0.4064)
			(end -0.7874 -0.4064)
			(stroke
				(width 0.1524)
				(type default)
			)
			(layer "F.SilkS")
		)
		(fp_line
			(start 0.7874 0.4064)
			(end -0.7874 0.4064)
			(stroke
				(width 0.1524)
				(type default)
			)
			(layer "F.SilkS")
		)
		(fp_line
			(start -0.7874 -0.4064)
			(end 0.7874 -0.4064)
			(stroke
				(width 0.1524)
				(type default)
			)
			(layer "F.SilkS")
		)
		(fp_line
			(start 0.7874 -0.4064)
			(end 0.7874 0.4064)
			(stroke
				(width 0.1524)
				(type default)
			)
			(layer "F.SilkS")
		)
		(fp_line
			(start -0.67945 0.3048)
			(end -0.67945 -0.305054)
			(stroke
				(width 0.1)
				(type default)
			)
			(layer "F.Fab")
		)
		(fp_line
			(start -0.12065 0.3048)
			(end -0.67945 0.3048)
			(stroke
				(width 0.1)
				(type default)
			)
			(layer "F.Fab")
		)
		(fp_line
			(start 0.120396 0.3048)
			(end 0.120396 0.2794)
			(stroke
				(width 0.1)
				(type default)
			)
			(layer "F.Fab")
		)
		(fp_line
			(start 0.67945 0.3048)
			(end 0.120396 0.3048)
			(stroke
				(width 0.1)
				(type default)
			)
			(layer "F.Fab")
		)
		(fp_line
			(start -0.12065 0.2794)
			(end -0.12065 0.3048)
			(stroke
				(width 0.1)
				(type default)
			)
			(layer "F.Fab")
		)
		(fp_line
			(start 0.120396 0.2794)
			(end -0.12065 0.2794)
			(stroke
				(width 0.1)
				(type default)
			)
			(layer "F.Fab")
		)
		(fp_line
			(start -0.12065 -0.2794)
			(end 0.12065 -0.2794)
			(stroke
				(width 0.1)
				(type default)
			)
			(layer "F.Fab")
		)
		(fp_line
			(start 0.12065 -0.2794)
			(end 0.12065 -0.3048)
			(stroke
				(width 0.1)
				(type default)
			)
			(layer "F.Fab")
		)
		(fp_line
			(start 0.12065 -0.3048)
			(end 0.67945 -0.3048)
			(stroke
				(width 0.1)
				(type default)
			)
			(layer "F.Fab")
		)
		(fp_line
			(start 0.67945 -0.3048)
			(end 0.67945 0.3048)
			(stroke
				(width 0.1)
				(type default)
			)
			(layer "F.Fab")
		)
		(fp_line
			(start -0.67945 -0.305054)
			(end -0.12065 -0.305054)
			(stroke
				(width 0.1)
				(type default)
			)
			(layer "F.Fab")
		)
		(fp_line
			(start -0.12065 -0.305054)
			(end -0.12065 -0.2794)
			(stroke
				(width 0.1)
				(type default)
			)
			(layer "F.Fab")
		)
		(pad "1" smd circle
			(at -0.40005 0 270)
			(size 0 0)
			(layers "F.Cu" "F.Mask" "F.Paste")
			(net "GND")
		)
		(pad "2" smd circle
			(at 0.40005 0 270)
			(size 0 0)
			(layers "F.Cu" "F.Mask" "F.Paste")
			(net "PEX0_DBG_MODE4")
		)
	)
)
